# BASEBOARD_FAB2 (Tioga Pass) — schematic netlist excerpt (pin names and nets, part order shuffled) for the footprints in the layout excerpt that follows; sources: Cadence DE-HDL packaged netlist, KiCad conversion of Wiwynn_Tioga_Pass_MB.brd

R12W12  665KR5B-1-GP  0.1%  pkg SMD-RG3  page 197 : \1\ = P12V_NVDIMM_GHJ_D ; \2\ = VR_PVDDQ_GHJ_VINSEN
R9P12  RES  4.99K 1% CHIP  pkg 0402  page 200 : A = A_HSC_INAP ; B = AGND_HSC

Q1W2  FET_N_DUAL  2N7002DW FET  pkg SMLF  page 250
  SOURCE(0)  = GND
  GATE(0)  = FM_OCP_MEZZB_PRES_N
  DRAIN(0)  = FM_OCP_MEZZB_PRES_1V05_PCH_N
  SOURCE(0)  = GND
  GATE(0)  = FM_OCP_MEZZB_PRES_LVT3_BMC
  DRAIN(0)  = FM_OCP_MEZZB_PRES_LVT3_BMC

(kicad_pcb
	(version 20260206)
	(generator "pcbnew")
	(generator_version "10.0")
	(general
		(thickness 1.6)
		(legacy_teardrops no)
	)
	(paper "A4")
	(title_block
		(title "Wiwynn_Tioga_Pass_MB.brd")
		(comment 1 "Tioga Pass / footprints 3860-3862 of 4770")
	)
	(layers
		(0 "F.Cu" signal "TOP")
		(4 "In1.Cu" signal "L2GND")
		(6 "In2.Cu" signal "L3")
		(8 "In3.Cu" signal "L4GND")
		(10 "In4.Cu" signal "L5")
		(12 "In5.Cu" signal "L6GND")
		(14 "In6.Cu" signal "L7VCC")
		(16 "In7.Cu" signal "L8VCC")
		(18 "In8.Cu" signal "L9GND")
		(20 "In9.Cu" signal "L10")
		(22 "In10.Cu" signal "L11GND")
		(24 "In11.Cu" signal "L12")
		(26 "In12.Cu" signal "L13GND")
		(2 "B.Cu" signal "BOTTOM")
		(9 "F.Adhes" user "F.Adhesive")
		(11 "B.Adhes" user "B.Adhesive")
		(13 "F.Paste" user "Package Geometry/Pastemask Top")
		(15 "B.Paste" user "Package Geometry/Pastemask Bottom")
		(5 "F.SilkS" user "Ref Des/Silkscreen Top")
		(7 "B.SilkS" user "Ref Des/Silkscreen Bottom")
		(1 "F.Mask" user "Board Geometry/Soldermask Top")
		(3 "B.Mask" user "Board Geometry/Soldermask Bottom")
		(17 "Dwgs.User" user "User.Drawings")
		(19 "Cmts.User" user "User.Comments")
		(21 "Eco1.User" user "User.Eco1")
		(23 "Eco2.User" user "User.Eco2")
		(25 "Edge.Cuts" user "Board Geometry/Outline")
		(27 "Margin" user)
		(31 "F.CrtYd" user "Package Geometry/Place Bound Top")
		(29 "B.CrtYd" user "Package Geometry/Place Bound Bottom")
		(35 "F.Fab" user "Ref Des/Assembly Top")
		(33 "B.Fab" user "Ref Des/Assembly Bottom")
	)
	(footprint ""
		(layer "B.Cu")
		(at 9.061958 3.20802)
		(property "Reference" "R12W12"
			(at 0 0 0)
			(layer "B.SilkS")
			(hide yes)
			(effects
				(font
					(size 1.27 1.27)
				)
				(justify mirror)
			)
		)
		(property "Value" "*"
			(at 0 -8.9535 0)
			(unlocked yes)
			(layer "B.Fab")
			(hide yes)
			(effects
				(font
					(size 1.27 1.016)
					(thickness 0.1524)
				)
				(justify mirror)
			)
		)
		(property "Device Type" "665KR5B-1-GP_SMD-RG3-665KR5B-1A"
			(at 0 -10.6299 0)
			(unlocked yes)
			(layer "B.Fab")
			(hide yes)
			(effects
				(font
					(size 1.27 1.016)
					(thickness 0.1524)
				)
				(justify mirror)
			)
		)
		(duplicate_pad_numbers_are_jumpers no)
		(fp_line
			(start -0.889 -1.7018)
			(end -0.889 -0.381)
			(stroke
				(width 0.1524)
				(type default)
			)
			(layer "B.SilkS")
		)
		(fp_line
			(start -0.889 -1.7018)
			(end 0.889 -1.7018)
			(stroke
				(width 0.1524)
				(type default)
			)
			(layer "B.SilkS")
		)
		(fp_line
			(start -0.889 1.7018)
			(end -0.889 -0.508)
			(stroke
				(width 0.1524)
				(type default)
			)
			(layer "B.SilkS")
		)
		(fp_line
			(start 0.889 -1.7018)
			(end 0.889 0.2794)
			(stroke
				(width 0.1524)
				(type default)
			)
			(layer "B.SilkS")
		)
		(fp_line
			(start 0.889 0.0762)
			(end 0.889 1.7018)
			(stroke
				(width 0.1524)
				(type default)
			)
			(layer "B.SilkS")
		)
		(fp_line
			(start 0.889 1.7018)
			(end -0.889 1.7018)
			(stroke
				(width 0.1524)
				(type default)
			)
			(layer "B.SilkS")
		)
		(fp_poly
			(pts
				(xy -0.9652 -1.778) (xy -0.9652 1.778) (xy 0.9652 1.778) (xy 0.9652 -1.778)
			)
			(stroke
				(width 0)
				(type default)
			)
			(fill no)
			(layer "B.CrtYd")
		)
		(fp_rect
			(start 0.9652 1.778)
			(end -0.9652 -1.778)
			(stroke
				(width 0)
				(type default)
			)
			(fill no)
			(layer "B.Fab")
		)
		(pad "1" smd rect
			(at 0 -0.9652 180)
			(size 1.397 1.143)
			(layers "B.Cu" "B.Mask" "B.Paste")
			(net "P12V_NVDIMM_GHJ_D")
		)
		(pad "2" smd rect
			(at 0 0.9652 180)
			(size 1.397 1.143)
			(layers "B.Cu" "B.Mask" "B.Paste")
			(net "VR_PVDDQ_GHJ_VINSEN")
		)
	)
	(footprint ""
		(layer "B.Cu")
		(at 23.114 -79.502 -90)
		(property "Reference" "R9P12"
			(at 0 0 90)
			(layer "B.SilkS")
			(hide yes)
			(effects
				(font
					(size 1.27 1.27)
				)
				(justify mirror)
			)
		)
		(property "Value" ""
			(at 0 0 90)
			(layer "B.Fab")
			(effects
				(font
					(size 1.27 1.27)
				)
				(justify mirror)
			)
		)
		(duplicate_pad_numbers_are_jumpers no)
		(fp_poly
			(pts
				(xy 0.2794 -0.1016) (xy -0.2794 -0.1016) (xy -0.2794 0.9906) (xy 0.2794 0.9906)
			)
			(stroke
				(width 0)
				(type default)
			)
			(fill no)
			(layer "B.CrtYd")
		)
		(fp_line
			(start -0.2794 0.9906)
			(end -0.2794 -0.1016)
			(stroke
				(width 0.1)
				(type default)
			)
			(layer "B.Fab")
		)
		(fp_line
			(start 0.2794 0.9906)
			(end -0.2794 0.9906)
			(stroke
				(width 0.1)
				(type default)
			)
			(layer "B.Fab")
		)
		(fp_line
			(start -0.2794 -0.1016)
			(end 0.2794 -0.1016)
			(stroke
				(width 0.1)
				(type default)
			)
			(layer "B.Fab")
		)
		(fp_line
			(start 0.2794 -0.1016)
			(end 0.2794 0.9906)
			(stroke
				(width 0.1)
				(type default)
			)
			(layer "B.Fab")
		)
		(pad "1" smd rect
			(at 0 0 90)
			(size 0.508 0.508)
			(layers "B.Cu" "B.Mask" "B.Paste")
			(net "A_HSC_INAP")
		)
		(pad "2" smd rect
			(at 0 0.889 90)
			(size 0.508 0.508)
			(layers "B.Cu" "B.Mask" "B.Paste")
			(net "AGND_HSC")
		)
		(zone
			(layer "B.Cu")
			(hatch none 0.5)
			(connect_pads
				(clearance 0)
			)
			(min_thickness 0.25)
			(keepout
				(tracks not_allowed)
				(vias allowed)
				(pads allowed)
				(copperpour not_allowed)
				(footprints allowed)
			)
			(placement
				(enabled no)
				(sheetname "")
			)
			(fill
				(thermal_gap 0.5)
				(thermal_bridge_width 0.5)
				(island_removal_mode 0)
			)
			(polygon
				(pts
					(xy 22.479 -79.248) (xy 22.479 -79.756) (xy 22.86 -79.756) (xy 22.86 -79.248)
				)
			)
		)
		(zone
			(layer "B.Cu")
			(hatch none 0.5)
			(connect_pads
				(clearance 0)
			)
			(min_thickness 0.25)
			(keepout
				(tracks allowed)
				(vias not_allowed)
				(pads allowed)
				(copperpour not_allowed)
				(footprints allowed)
			)
			(placement
				(enabled no)
				(sheetname "")
			)
			(fill
				(thermal_gap 0.5)
				(thermal_bridge_width 0.5)
				(island_removal_mode 0)
			)
			(polygon
				(pts
					(xy 22.86 -79.248) (xy 22.86 -79.756) (xy 22.479 -79.756) (xy 22.479 -79.248)
				)
			)
		)
	)
	(footprint ""
		(layer "B.Cu")
		(at 406.7048 -53.848 -90)
		(property "Reference" "Q1W2"
			(at 0 -0.81788 270)
			(unlocked yes)
			(layer "B.SilkS")
			(effects
				(font
					(size 0.4064 0.254)
					(thickness 0.1524)
				)
				(justify left mirror)
			)
		)
		(property "Value" ""
			(at 0 0 90)
			(layer "B.Fab")
			(effects
				(font
					(size 1.27 1.27)
				)
				(justify mirror)
			)
		)
		(duplicate_pad_numbers_are_jumpers no)
		(fp_circle
			(center 0.848614 -0.6477)
			(end 0.848614 -0.7747)
			(stroke
				(width 0.254)
				(type default)
			)
			(fill no)
			(layer "B.SilkS")
		)
		(fp_poly
			(pts
				(xy -0.21463 -0.450088) (xy -1.56337 -0.450088) (xy -1.56337 1.75006) (xy -0.21463 1.75006)
			)
			(stroke
				(width 0)
				(type default)
			)
			(fill no)
			(layer "B.CrtYd")
		)
		(fp_line
			(start -1.56337 1.75006)
			(end -0.21463 1.75006)
			(stroke
				(width 0.1)
				(type default)
			)
			(layer "B.Fab")
		)
		(fp_line
			(start -0.21463 1.75006)
			(end -0.21463 -0.450088)
			(stroke
				(width 0.1)
				(type default)
			)
			(layer "B.Fab")
		)
		(fp_line
			(start -1.56337 -0.450088)
			(end -1.56337 1.75006)
			(stroke
				(width 0.1)
				(type default)
			)
			(layer "B.Fab")
		)
		(fp_line
			(start -0.21463 -0.450088)
			(end -1.56337 -0.450088)
			(stroke
				(width 0.1)
				(type default)
			)
			(layer "B.Fab")
		)
		(fp_circle
			(center 0.848614 -0.6477)
			(end 0.848614 -0.7747)
			(stroke
				(width 0.254)
				(type default)
			)
			(fill no)
			(layer "B.Fab")
		)
		(pad "1" smd rect
			(at 0 0 90)
			(size 1.016 0.381)
			(layers "B.Cu" "B.Mask" "B.Paste")
			(net "GND")
		)
		(pad "2" smd rect
			(at 0 0.649986 90)
			(size 1.016 0.381)
			(layers "B.Cu" "B.Mask" "B.Paste")
			(net "FM_OCP_MEZZB_PRES_N")
		)
		(pad "3" smd rect
			(at 0 1.299972 90)
			(size 1.016 0.381)
			(layers "B.Cu" "B.Mask" "B.Paste")
			(net "FM_OCP_MEZZB_PRES_1V05_PCH_N")
		)
		(pad "4" smd rect
			(at -1.778 1.299972 90)
			(size 1.016 0.381)
			(layers "B.Cu" "B.Mask" "B.Paste")
			(net "GND")
		)
		(pad "5" smd rect
			(at -1.778 0.649986 90)
			(size 1.016 0.381)
			(layers "B.Cu" "B.Mask" "B.Paste")
			(net "FM_OCP_MEZZB_PRES_LVT3_BMC")
		)
		(pad "6" smd rect
			(at -1.778 0 90)
			(size 1.016 0.381)
			(layers "B.Cu" "B.Mask" "B.Paste")
			(net "FM_OCP_MEZZB_PRES_LVT3_BMC")
		)
	)
)
